(kicad_pcb
	(version 20260206)
	(generator "pcbnew")
	(generator_version "10.0")
	(general
		(thickness 1.6)
		(legacy_teardrops no)
	)
	(paper "A4")
	(title_block
		(title "01162023_DA0F0TEBIF0_F0T_Expander_BD_F_brd_V02_OCP.brd")
		(comment 1 "Grand Teton / footprints 7853-7863 of 9728")
	)
	(layers
		(0 "F.Cu" signal "TOP")
		(4 "In1.Cu" signal "GND")
		(6 "In2.Cu" signal "VCC")
		(8 "In3.Cu" signal "VCC1")
		(10 "In4.Cu" signal "GND1")
		(12 "In5.Cu" signal "IN1")
		(14 "In6.Cu" signal "GND2")
		(16 "In7.Cu" signal "IN2")
		(18 "In8.Cu" signal "GND3")
		(20 "In9.Cu" signal "IN3")
		(22 "In10.Cu" signal "GND4")
		(24 "In11.Cu" signal "IN4")
		(26 "In12.Cu" signal "GND5")
		(28 "In13.Cu" signal "IN5")
		(30 "In14.Cu" signal "GND6")
		(32 "In15.Cu" signal "IN6")
		(34 "In16.Cu" signal "GND7")
		(2 "B.Cu" signal "BOTTOM")
		(9 "F.Adhes" user "F.Adhesive")
		(11 "B.Adhes" user "B.Adhesive")
		(13 "F.Paste" user "Package Geometry/Pastemask Top")
		(15 "B.Paste" user "Package Geometry/Pastemask Bottom")
		(5 "F.SilkS" user "Ref Des/Silkscreen Top")
		(7 "B.SilkS" user "Ref Des/Silkscreen Bottom")
		(1 "F.Mask" user "Board Geometry/Soldermask Top")
		(3 "B.Mask" user "Board Geometry/Soldermask Bottom")
		(17 "Dwgs.User" user "User.Drawings")
		(19 "Cmts.User" user "User.Comments")
		(21 "Eco1.User" user "User.Eco1")
		(23 "Eco2.User" user "User.Eco2")
		(25 "Edge.Cuts" user "Board Geometry/Outline")
		(27 "Margin" user)
		(31 "F.CrtYd" user "Package Geometry/Place Bound Top")
		(29 "B.CrtYd" user "Package Geometry/Place Bound Bottom")
		(35 "F.Fab" user "Ref Des/Assembly Top")
		(33 "B.Fab" user "Ref Des/Assembly Bottom")
	)
	(footprint ""
		(layer "B.Cu")
		(at 398.925034 -286.399732 90)
		(property "Reference" "C3472"
			(at 0 0 90)
			(layer "B.SilkS")
			(hide yes)
			(effects
				(font
					(size 1.27 1.27)
				)
				(justify mirror)
			)
		)
		(property "Value" ""
			(at 0 0 90)
			(layer "B.Fab")
			(effects
				(font
					(size 1.27 1.27)
				)
				(justify mirror)
			)
		)
		(duplicate_pad_numbers_are_jumpers no)
		(fp_line
			(start 0.299974 -0.150114)
			(end -0.299974 -0.150114)
			(stroke
				(width 0.1)
				(type default)
			)
			(layer "B.Fab")
		)
		(fp_line
			(start -0.299974 -0.150114)
			(end -0.299974 0.150114)
			(stroke
				(width 0.1)
				(type default)
			)
			(layer "B.Fab")
		)
		(fp_line
			(start 0.299974 0.150114)
			(end 0.299974 -0.150114)
			(stroke
				(width 0.1)
				(type default)
			)
			(layer "B.Fab")
		)
		(fp_line
			(start -0.299974 0.150114)
			(end 0.299974 0.150114)
			(stroke
				(width 0.1)
				(type default)
			)
			(layer "B.Fab")
		)
		(pad "1" smd rect
			(at 0.2667 0 270)
			(size 0.3048 0.381)
			(layers "B.Cu" "B.Mask" "B.Paste")
			(net "P1V25_SERDES_VDDPLL_PEX3")
		)
		(pad "2" smd rect
			(at -0.2667 0 270)
			(size 0.3048 0.381)
			(layers "B.Cu" "B.Mask" "B.Paste")
			(net "GND")
		)
	)
	(footprint ""
		(layer "B.Cu")
		(at 66.299842 -292.099746 90)
		(property "Reference" "C1195"
			(at 0 0 90)
			(layer "B.SilkS")
			(hide yes)
			(effects
				(font
					(size 1.27 1.27)
				)
				(justify mirror)
			)
		)
		(property "Value" ""
			(at 0 0 90)
			(layer "B.Fab")
			(effects
				(font
					(size 1.27 1.27)
				)
				(justify mirror)
			)
		)
		(duplicate_pad_numbers_are_jumpers no)
		(fp_line
			(start 0.299974 -0.150114)
			(end -0.299974 -0.150114)
			(stroke
				(width 0.1)
				(type default)
			)
			(layer "B.Fab")
		)
		(fp_line
			(start -0.299974 -0.150114)
			(end -0.299974 0.150114)
			(stroke
				(width 0.1)
				(type default)
			)
			(layer "B.Fab")
		)
		(fp_line
			(start 0.299974 0.150114)
			(end 0.299974 -0.150114)
			(stroke
				(width 0.1)
				(type default)
			)
			(layer "B.Fab")
		)
		(fp_line
			(start -0.299974 0.150114)
			(end 0.299974 0.150114)
			(stroke
				(width 0.1)
				(type default)
			)
			(layer "B.Fab")
		)
		(pad "1" smd rect
			(at 0.2667 0 270)
			(size 0.3048 0.381)
			(layers "B.Cu" "B.Mask" "B.Paste")
			(net "P0V8_SERDES_VDDA_PEX0")
		)
		(pad "2" smd rect
			(at -0.2667 0 270)
			(size 0.3048 0.381)
			(layers "B.Cu" "B.Mask" "B.Paste")
			(net "GND")
		)
	)
	(footprint ""
		(layer "B.Cu")
		(at 121.619772 -284.796738 -90)
		(property "Reference" "PC94"
			(at 0 0 90)
			(layer "B.SilkS")
			(hide yes)
			(effects
				(font
					(size 1.27 1.27)
				)
				(justify mirror)
			)
		)
		(property "Value" ""
			(at 0 0 90)
			(layer "B.Fab")
			(effects
				(font
					(size 1.27 1.27)
				)
				(justify mirror)
			)
		)
		(duplicate_pad_numbers_are_jumpers no)
		(fp_line
			(start -1.524 0.762)
			(end 1.524 0.762)
			(stroke
				(width 0.1524)
				(type default)
			)
			(layer "B.SilkS")
		)
		(fp_line
			(start 1.524 0.762)
			(end 1.524 -0.762)
			(stroke
				(width 0.1524)
				(type default)
			)
			(layer "B.SilkS")
		)
		(fp_line
			(start -1.524 -0.762)
			(end -1.524 0.762)
			(stroke
				(width 0.1524)
				(type default)
			)
			(layer "B.SilkS")
		)
		(fp_line
			(start 1.524 -0.762)
			(end -1.524 -0.762)
			(stroke
				(width 0.1524)
				(type default)
			)
			(layer "B.SilkS")
		)
		(fp_line
			(start -1.1049 0.724916)
			(end -1.1049 -0.724916)
			(stroke
				(width 0.1)
				(type default)
			)
			(layer "B.Fab")
		)
		(fp_line
			(start 1.1049 0.724916)
			(end -1.1049 0.724916)
			(stroke
				(width 0.1)
				(type default)
			)
			(layer "B.Fab")
		)
		(fp_line
			(start -1.1049 -0.724916)
			(end 1.1049 -0.724916)
			(stroke
				(width 0.1)
				(type default)
			)
			(layer "B.Fab")
		)
		(fp_line
			(start 1.1049 -0.724916)
			(end 1.1049 0.724916)
			(stroke
				(width 0.1)
				(type default)
			)
			(layer "B.Fab")
		)
		(pad "1" smd rect
			(at 0.889 0 270)
			(size 1.016 1.27)
			(layers "B.Cu" "B.Mask" "B.Paste")
			(net "SW_P12V_P0V8_PEX1_FLT")
		)
		(pad "2" smd rect
			(at -0.889 0 270)
			(size 1.016 1.27)
			(layers "B.Cu" "B.Mask" "B.Paste")
			(net "GND")
		)
	)
	(footprint ""
		(layer "B.Cu")
		(at 211.553298 -371.77726 180)
		(property "Reference" "PR21"
			(at 0 0 0)
			(layer "B.SilkS")
			(hide yes)
			(effects
				(font
					(size 1.27 1.27)
				)
				(justify mirror)
			)
		)
		(property "Value" ""
			(at 0 0 0)
			(layer "B.Fab")
			(effects
				(font
					(size 1.27 1.27)
				)
				(justify mirror)
			)
		)
		(duplicate_pad_numbers_are_jumpers no)
		(fp_line
			(start 0.7874 0.4064)
			(end 0.7874 -0.4064)
			(stroke
				(width 0.1524)
				(type default)
			)
			(layer "B.SilkS")
		)
		(fp_line
			(start 0.7874 -0.4064)
			(end -0.7874 -0.4064)
			(stroke
				(width 0.1524)
				(type default)
			)
			(layer "B.SilkS")
		)
		(fp_line
			(start -0.7874 0.4064)
			(end 0.7874 0.4064)
			(stroke
				(width 0.1524)
				(type default)
			)
			(layer "B.SilkS")
		)
		(fp_line
			(start -0.7874 -0.4064)
			(end -0.7874 0.4064)
			(stroke
				(width 0.1524)
				(type default)
			)
			(layer "B.SilkS")
		)
		(fp_line
			(start 0.67945 0.3048)
			(end 0.67945 -0.305054)
			(stroke
				(width 0.1)
				(type default)
			)
			(layer "B.Fab")
		)
		(fp_line
			(start 0.67945 -0.305054)
			(end 0.12065 -0.305054)
			(stroke
				(width 0.1)
				(type default)
			)
			(layer "B.Fab")
		)
		(fp_line
			(start 0.12065 0.3048)
			(end 0.67945 0.3048)
			(stroke
				(width 0.1)
				(type default)
			)
			(layer "B.Fab")
		)
		(fp_line
			(start 0.12065 0.2794)
			(end 0.12065 0.3048)
			(stroke
				(width 0.1)
				(type default)
			)
			(layer "B.Fab")
		)
		(fp_line
			(start 0.12065 -0.2794)
			(end -0.12065 -0.2794)
			(stroke
				(width 0.1)
				(type default)
			)
			(layer "B.Fab")
		)
		(fp_line
			(start 0.12065 -0.305054)
			(end 0.12065 -0.2794)
			(stroke
				(width 0.1)
				(type default)
			)
			(layer "B.Fab")
		)
		(fp_line
			(start -0.120396 0.3048)
			(end -0.120396 0.2794)
			(stroke
				(width 0.1)
				(type default)
			)
			(layer "B.Fab")
		)
		(fp_line
			(start -0.120396 0.2794)
			(end 0.12065 0.2794)
			(stroke
				(width 0.1)
				(type default)
			)
			(layer "B.Fab")
		)
		(fp_line
			(start -0.12065 -0.2794)
			(end -0.12065 -0.3048)
			(stroke
				(width 0.1)
				(type default)
			)
			(layer "B.Fab")
		)
		(fp_line
			(start -0.12065 -0.3048)
			(end -0.67945 -0.3048)
			(stroke
				(width 0.1)
				(type default)
			)
			(layer "B.Fab")
		)
		(fp_line
			(start -0.67945 0.3048)
			(end -0.120396 0.3048)
			(stroke
				(width 0.1)
				(type default)
			)
			(layer "B.Fab")
		)
		(fp_line
			(start -0.67945 -0.3048)
			(end -0.67945 0.3048)
			(stroke
				(width 0.1)
				(type default)
			)
			(layer "B.Fab")
		)
		(pad "1" smd circle
			(at 0.40005 0)
			(size 0 0)
			(layers "B.Cu" "B.Mask" "B.Paste")
			(net "HSC_FLT_TYPE")
		)
		(pad "2" smd circle
			(at -0.40005 0)
			(size 0 0)
			(layers "B.Cu" "B.Mask" "B.Paste")
			(net "HSC_FLT_TYPE_R")
		)
	)
	(footprint ""
		(layer "B.Cu")
		(at 168.625012 -305.399948 -90)
		(property "Reference" "C3155"
			(at 0 0 90)
			(layer "B.SilkS")
			(hide yes)
			(effects
				(font
					(size 1.27 1.27)
				)
				(justify mirror)
			)
		)
		(property "Value" ""
			(at 0 0 90)
			(layer "B.Fab")
			(effects
				(font
					(size 1.27 1.27)
				)
				(justify mirror)
			)
		)
		(duplicate_pad_numbers_are_jumpers no)
		(fp_line
			(start -0.299974 0.150114)
			(end 0.299974 0.150114)
			(stroke
				(width 0.1)
				(type default)
			)
			(layer "B.Fab")
		)
		(fp_line
			(start 0.299974 0.150114)
			(end 0.299974 -0.150114)
			(stroke
				(width 0.1)
				(type default)
			)
			(layer "B.Fab")
		)
		(fp_line
			(start -0.299974 -0.150114)
			(end -0.299974 0.150114)
			(stroke
				(width 0.1)
				(type default)
			)
			(layer "B.Fab")
		)
		(fp_line
			(start 0.299974 -0.150114)
			(end -0.299974 -0.150114)
			(stroke
				(width 0.1)
				(type default)
			)
			(layer "B.Fab")
		)
		(pad "1" smd rect
			(at 0.2667 0 90)
			(size 0.3048 0.381)
			(layers "B.Cu" "B.Mask" "B.Paste")
			(net "P1V25_SERDES_VDDPLL_PEX1")
		)
		(pad "2" smd rect
			(at -0.2667 0 90)
			(size 0.3048 0.381)
			(layers "B.Cu" "B.Mask" "B.Paste")
			(net "GND")
		)
	)
	(footprint ""
		(layer "B.Cu")
		(at 276.649688 -293.99992)
		(property "Reference" "C3335"
			(at 0 0 0)
			(layer "B.SilkS")
			(hide yes)
			(effects
				(font
					(size 1.27 1.27)
				)
				(justify mirror)
			)
		)
		(property "Value" ""
			(at 0 0 0)
			(layer "B.Fab")
			(effects
				(font
					(size 1.27 1.27)
				)
				(justify mirror)
			)
		)
		(duplicate_pad_numbers_are_jumpers no)
		(fp_line
			(start -0.299974 -0.150114)
			(end -0.299974 0.150114)
			(stroke
				(width 0.1)
				(type default)
			)
			(layer "B.Fab")
		)
		(fp_line
			(start -0.299974 0.150114)
			(end 0.299974 0.150114)
			(stroke
				(width 0.1)
				(type default)
			)
			(layer "B.Fab")
		)
		(fp_line
			(start 0.299974 -0.150114)
			(end -0.299974 -0.150114)
			(stroke
				(width 0.1)
				(type default)
			)
			(layer "B.Fab")
		)
		(fp_line
			(start 0.299974 0.150114)
			(end 0.299974 -0.150114)
			(stroke
				(width 0.1)
				(type default)
			)
			(layer "B.Fab")
		)
		(pad "1" smd rect
			(at 0.2667 0 180)
			(size 0.3048 0.381)
			(layers "B.Cu" "B.Mask" "B.Paste")
			(net "P1V8_PEX")
		)
		(pad "2" smd rect
			(at -0.2667 0 180)
			(size 0.3048 0.381)
			(layers "B.Cu" "B.Mask" "B.Paste")
			(net "GND")
		)
	)
	(footprint ""
		(layer "B.Cu")
		(at 68.199762 -298.27474 180)
		(property "Reference" "C1126"
			(at 0 0 0)
			(layer "B.SilkS")
			(hide yes)
			(effects
				(font
					(size 1.27 1.27)
				)
				(justify mirror)
			)
		)
		(property "Value" ""
			(at 0 0 0)
			(layer "B.Fab")
			(effects
				(font
					(size 1.27 1.27)
				)
				(justify mirror)
			)
		)
		(duplicate_pad_numbers_are_jumpers no)
		(fp_line
			(start 0.299974 0.150114)
			(end 0.299974 -0.150114)
			(stroke
				(width 0.1)
				(type default)
			)
			(layer "B.Fab")
		)
		(fp_line
			(start 0.299974 -0.150114)
			(end -0.299974 -0.150114)
			(stroke
				(width 0.1)
				(type default)
			)
			(layer "B.Fab")
		)
		(fp_line
			(start -0.299974 0.150114)
			(end 0.299974 0.150114)
			(stroke
				(width 0.1)
				(type default)
			)
			(layer "B.Fab")
		)
		(fp_line
			(start -0.299974 -0.150114)
			(end -0.299974 0.150114)
			(stroke
				(width 0.1)
				(type default)
			)
			(layer "B.Fab")
		)
		(pad "1" smd rect
			(at 0.2667 0)
			(size 0.3048 0.381)
			(layers "B.Cu" "B.Mask" "B.Paste")
			(net "P0V8_PEX0")
		)
		(pad "2" smd rect
			(at -0.2667 0)
			(size 0.3048 0.381)
			(layers "B.Cu" "B.Mask" "B.Paste")
			(net "GND")
		)
	)
	(footprint ""
		(layer "B.Cu")
		(at 108.441236 -303.649634 -90)
		(property "Reference" "PC84"
			(at 0 0 90)
			(layer "B.SilkS")
			(hide yes)
			(effects
				(font
					(size 1.27 1.27)
				)
				(justify mirror)
			)
		)
		(property "Value" ""
			(at 0 0 90)
			(layer "B.Fab")
			(effects
				(font
					(size 1.27 1.27)
				)
				(justify mirror)
			)
		)
		(duplicate_pad_numbers_are_jumpers no)
		(fp_line
			(start -1.524 0.762)
			(end 1.524 0.762)
			(stroke
				(width 0.1524)
				(type default)
			)
			(layer "B.SilkS")
		)
		(fp_line
			(start 1.524 0.762)
			(end 1.524 -0.762)
			(stroke
				(width 0.1524)
				(type default)
			)
			(layer "B.SilkS")
		)
		(fp_line
			(start -1.524 -0.762)
			(end -1.524 0.762)
			(stroke
				(width 0.1524)
				(type default)
			)
			(layer "B.SilkS")
		)
		(fp_line
			(start 1.524 -0.762)
			(end -1.524 -0.762)
			(stroke
				(width 0.1524)
				(type default)
			)
			(layer "B.SilkS")
		)
		(fp_line
			(start -1.1049 0.724916)
			(end -1.1049 -0.724916)
			(stroke
				(width 0.1)
				(type default)
			)
			(layer "B.Fab")
		)
		(fp_line
			(start 1.1049 0.724916)
			(end -1.1049 0.724916)
			(stroke
				(width 0.1)
				(type default)
			)
			(layer "B.Fab")
		)
		(fp_line
			(start -1.1049 -0.724916)
			(end 1.1049 -0.724916)
			(stroke
				(width 0.1)
				(type default)
			)
			(layer "B.Fab")
		)
		(fp_line
			(start 1.1049 -0.724916)
			(end 1.1049 0.724916)
			(stroke
				(width 0.1)
				(type default)
			)
			(layer "B.Fab")
		)
		(pad "1" smd rect
			(at 0.889 0 270)
			(size 1.016 1.27)
			(layers "B.Cu" "B.Mask" "B.Paste")
			(net "P0V8_PEX0")
		)
		(pad "2" smd rect
			(at -0.889 0 270)
			(size 1.016 1.27)
			(layers "B.Cu" "B.Mask" "B.Paste")
			(net "GND")
		)
	)
	(footprint ""
		(layer "B.Cu")
		(at 225.857308 -146.631152 180)
		(property "Reference" "C2802"
			(at 0 0 0)
			(layer "B.SilkS")
			(hide yes)
			(effects
				(font
					(size 1.27 1.27)
				)
				(justify mirror)
			)
		)
		(property "Value" ""
			(at 0 0 0)
			(layer "B.Fab")
			(effects
				(font
					(size 1.27 1.27)
				)
				(justify mirror)
			)
		)
		(duplicate_pad_numbers_are_jumpers no)
		(fp_line
			(start 0.7874 0.4064)
			(end 0.7874 -0.4064)
			(stroke
				(width 0.1524)
				(type default)
			)
			(layer "B.SilkS")
		)
		(fp_line
			(start 0.7874 -0.4064)
			(end -0.7874 -0.4064)
			(stroke
				(width 0.1524)
				(type default)
			)
			(layer "B.SilkS")
		)
		(fp_line
			(start -0.7874 0.4064)
			(end 0.7874 0.4064)
			(stroke
				(width 0.1524)
				(type default)
			)
			(layer "B.SilkS")
		)
		(fp_line
			(start -0.7874 -0.4064)
			(end -0.7874 0.4064)
			(stroke
				(width 0.1524)
				(type default)
			)
			(layer "B.SilkS")
		)
		(fp_line
			(start 0.67945 0.3048)
			(end 0.67945 -0.305054)
			(stroke
				(width 0.1)
				(type default)
			)
			(layer "B.Fab")
		)
		(fp_line
			(start 0.67945 -0.305054)
			(end 0.12065 -0.305054)
			(stroke
				(width 0.1)
				(type default)
			)
			(layer "B.Fab")
		)
		(fp_line
			(start 0.12065 0.3048)
			(end 0.67945 0.3048)
			(stroke
				(width 0.1)
				(type default)
			)
			(layer "B.Fab")
		)
		(fp_line
			(start 0.12065 0.2794)
			(end 0.12065 0.3048)
			(stroke
				(width 0.1)
				(type default)
			)
			(layer "B.Fab")
		)
		(fp_line
			(start 0.12065 -0.2794)
			(end -0.12065 -0.2794)
			(stroke
				(width 0.1)
				(type default)
			)
			(layer "B.Fab")
		)
		(fp_line
			(start 0.12065 -0.305054)
			(end 0.12065 -0.2794)
			(stroke
				(width 0.1)
				(type default)
			)
			(layer "B.Fab")
		)
		(fp_line
			(start -0.120396 0.3048)
			(end -0.120396 0.2794)
			(stroke
				(width 0.1)
				(type default)
			)
			(layer "B.Fab")
		)
		(fp_line
			(start -0.120396 0.2794)
			(end 0.12065 0.2794)
			(stroke
				(width 0.1)
				(type default)
			)
			(layer "B.Fab")
		)
		(fp_line
			(start -0.12065 -0.2794)
			(end -0.12065 -0.3048)
			(stroke
				(width 0.1)
				(type default)
			)
			(layer "B.Fab")
		)
		(fp_line
			(start -0.12065 -0.3048)
			(end -0.67945 -0.3048)
			(stroke
				(width 0.1)
				(type default)
			)
			(layer "B.Fab")
		)
		(fp_line
			(start -0.67945 0.3048)
			(end -0.120396 0.3048)
			(stroke
				(width 0.1)
				(type default)
			)
			(layer "B.Fab")
		)
		(fp_line
			(start -0.67945 -0.3048)
			(end -0.67945 0.3048)
			(stroke
				(width 0.1)
				(type default)
			)
			(layer "B.Fab")
		)
		(pad "1" smd circle
			(at 0.40005 0)
			(size 0 0)
			(layers "B.Cu" "B.Mask" "B.Paste")
			(net "P3V3_CLK_GEN_VDDMXCK_CK440_PEX")
		)
		(pad "2" smd circle
			(at -0.40005 0)
			(size 0 0)
			(layers "B.Cu" "B.Mask" "B.Paste")
			(net "GND")
		)
	)
	(footprint ""
		(layer "B.Cu")
		(at 410.351224 -305.399948 -90)
		(property "Reference" "C3486"
			(at 0 0 90)
			(layer "B.SilkS")
			(hide yes)
			(effects
				(font
					(size 1.27 1.27)
				)
				(justify mirror)
			)
		)
		(property "Value" ""
			(at 0 0 90)
			(layer "B.Fab")
			(effects
				(font
					(size 1.27 1.27)
				)
				(justify mirror)
			)
		)
		(duplicate_pad_numbers_are_jumpers no)
		(fp_line
			(start -0.299974 0.150114)
			(end 0.299974 0.150114)
			(stroke
				(width 0.1)
				(type default)
			)
			(layer "B.Fab")
		)
		(fp_line
			(start 0.299974 0.150114)
			(end 0.299974 -0.150114)
			(stroke
				(width 0.1)
				(type default)
			)
			(layer "B.Fab")
		)
		(fp_line
			(start -0.299974 -0.150114)
			(end -0.299974 0.150114)
			(stroke
				(width 0.1)
				(type default)
			)
			(layer "B.Fab")
		)
		(fp_line
			(start 0.299974 -0.150114)
			(end -0.299974 -0.150114)
			(stroke
				(width 0.1)
				(type default)
			)
			(layer "B.Fab")
		)
		(pad "1" smd rect
			(at 0.2667 0 90)
			(size 0.3048 0.381)
			(layers "B.Cu" "B.Mask" "B.Paste")
			(net "P1V25_SERDES_VDDPLL_PEX3")
		)
		(pad "2" smd rect
			(at -0.2667 0 90)
			(size 0.3048 0.381)
			(layers "B.Cu" "B.Mask" "B.Paste")
			(net "GND")
		)
	)
	(footprint ""
		(layer "B.Cu")
		(at 366.46993 -308.677818 90)
		(property "Reference" "C4363"
			(at 0 0 90)
			(layer "B.SilkS")
			(hide yes)
			(effects
				(font
					(size 1.27 1.27)
				)
				(justify mirror)
			)
		)
		(property "Value" ""
			(at 0 0 90)
			(layer "B.Fab")
			(effects
				(font
					(size 1.27 1.27)
				)
				(justify mirror)
			)
		)
		(duplicate_pad_numbers_are_jumpers no)
		(fp_line
			(start 0.299974 -0.150114)
			(end -0.299974 -0.150114)
			(stroke
				(width 0.1)
				(type default)
			)
			(layer "B.Fab")
		)
		(fp_line
			(start -0.299974 -0.150114)
			(end -0.299974 0.150114)
			(stroke
				(width 0.1)
				(type default)
			)
			(layer "B.Fab")
		)
		(fp_line
			(start 0.299974 0.150114)
			(end 0.299974 -0.150114)
			(stroke
				(width 0.1)
				(type default)
			)
			(layer "B.Fab")
		)
		(fp_line
			(start -0.299974 0.150114)
			(end 0.299974 0.150114)
			(stroke
				(width 0.1)
				(type default)
			)
			(layer "B.Fab")
		)
		(pad "1" smd rect
			(at 0.2667 0 270)
			(size 0.3048 0.381)
			(layers "B.Cu" "B.Mask" "B.Paste")
			(net "P0V8_PEX3")
		)
		(pad "2" smd rect
			(at -0.2667 0 270)
			(size 0.3048 0.381)
			(layers "B.Cu" "B.Mask" "B.Paste")
			(net "GND")
		)
	)
)
